# S9S_MB_2U (Grand Teton) — schematic netlist excerpt (pin names and nets, part order shuffled) for the footprints in the layout excerpt that follows; sources: Cadence DE-HDL packaged netlist, KiCad conversion of 03242023_DA0F0TMBIJ0_F0T_Motherboard_J_brd_V01_OCP.brd

C37  Q_CAP  10UF 16V 10% X6S  pkg C0805  page 93 : A = P12V_S3_AUX_CPU0_NVDIMM ; B = GND
PR4255  Q_RES  0 5% CHIP  pkg 0402LF  page 296 : A = NC_PVCCD_HV_CPU1_ACSP6 ; B = GND
C1389  Q_CAP  47UF 2.5V 20% X6S  pkg C0603  page 78 : A = PVNN_MAIN_CPU1 ; B = GND

(kicad_pcb
	(version 20260206)
	(generator "pcbnew")
	(generator_version "10.0")
	(general
		(thickness 1.6)
		(legacy_teardrops no)
	)
	(paper "A4")
	(title_block
		(title "03242023_DA0F0TMBIJ0_F0T_Motherboard_J_brd_V01_OCP.brd")
		(comment 1 "Grand Teton / footprints 4707-4709 of 6105")
	)
	(layers
		(0 "F.Cu" signal "TOP")
		(4 "In1.Cu" signal "GND")
		(6 "In2.Cu" signal "IN1")
		(8 "In3.Cu" signal "GND1")
		(10 "In4.Cu" signal "IN2")
		(12 "In5.Cu" signal "GND2")
		(14 "In6.Cu" signal "IN3")
		(16 "In7.Cu" signal "GND3")
		(18 "In8.Cu" signal "VCC")
		(20 "In9.Cu" signal "VCC1")
		(22 "In10.Cu" signal "GND4")
		(24 "In11.Cu" signal "IN4")
		(26 "In12.Cu" signal "GND5")
		(28 "In13.Cu" signal "IN5")
		(30 "In14.Cu" signal "GND6")
		(32 "In15.Cu" signal "IN6")
		(34 "In16.Cu" signal "GND7")
		(2 "B.Cu" signal "BOTTOM")
		(9 "F.Adhes" user "F.Adhesive")
		(11 "B.Adhes" user "B.Adhesive")
		(13 "F.Paste" user "Package Geometry/Pastemask Top")
		(15 "B.Paste" user "Package Geometry/Pastemask Bottom")
		(5 "F.SilkS" user "Ref Des/Silkscreen Top")
		(7 "B.SilkS" user "Ref Des/Silkscreen Bottom")
		(1 "F.Mask" user "Board Geometry/Soldermask Top")
		(3 "B.Mask" user "Board Geometry/Soldermask Bottom")
		(17 "Dwgs.User" user "User.Drawings")
		(19 "Cmts.User" user "User.Comments")
		(21 "Eco1.User" user "User.Eco1")
		(23 "Eco2.User" user "User.Eco2")
		(25 "Edge.Cuts" user "Board Geometry/Outline")
		(27 "Margin" user)
		(31 "F.CrtYd" user "Package Geometry/Place Bound Top")
		(29 "B.CrtYd" user "Package Geometry/Place Bound Bottom")
		(35 "F.Fab" user "Ref Des/Assembly Top")
		(33 "B.Fab" user "Ref Des/Assembly Bottom")
	)
	(footprint ""
		(layer "B.Cu")
		(at 425.917614 -321.549776 -90)
		(property "Reference" "C37"
			(at 0 0 90)
			(layer "B.SilkS")
			(hide yes)
			(effects
				(font
					(size 1.27 1.27)
				)
				(justify mirror)
			)
		)
		(property "Value" ""
			(at 0 0 90)
			(layer "B.Fab")
			(effects
				(font
					(size 1.27 1.27)
				)
				(justify mirror)
			)
		)
		(duplicate_pad_numbers_are_jumpers no)
		(fp_line
			(start -1.524 0.762)
			(end 1.524 0.762)
			(stroke
				(width 0.1524)
				(type default)
			)
			(layer "B.SilkS")
		)
		(fp_line
			(start 1.524 0.762)
			(end 1.524 -0.762)
			(stroke
				(width 0.1524)
				(type default)
			)
			(layer "B.SilkS")
		)
		(fp_line
			(start -1.524 -0.762)
			(end -1.524 0.762)
			(stroke
				(width 0.1524)
				(type default)
			)
			(layer "B.SilkS")
		)
		(fp_line
			(start 1.524 -0.762)
			(end -1.524 -0.762)
			(stroke
				(width 0.1524)
				(type default)
			)
			(layer "B.SilkS")
		)
		(fp_line
			(start -1.1049 0.724916)
			(end -1.1049 -0.724916)
			(stroke
				(width 0.1)
				(type default)
			)
			(layer "B.Fab")
		)
		(fp_line
			(start 1.1049 0.724916)
			(end -1.1049 0.724916)
			(stroke
				(width 0.1)
				(type default)
			)
			(layer "B.Fab")
		)
		(fp_line
			(start -1.1049 -0.724916)
			(end 1.1049 -0.724916)
			(stroke
				(width 0.1)
				(type default)
			)
			(layer "B.Fab")
		)
		(fp_line
			(start 1.1049 -0.724916)
			(end 1.1049 0.724916)
			(stroke
				(width 0.1)
				(type default)
			)
			(layer "B.Fab")
		)
		(pad "1" smd rect
			(at 0.889 0 270)
			(size 1.016 1.27)
			(layers "B.Cu" "B.Mask" "B.Paste")
			(net "P12V_S3_AUX_CPU0_NVDIMM")
		)
		(pad "2" smd rect
			(at -0.889 0 270)
			(size 1.016 1.27)
			(layers "B.Cu" "B.Mask" "B.Paste")
			(net "GND")
		)
	)
	(footprint ""
		(layer "B.Cu")
		(at 27.7368 -162.270948 -90)
		(property "Reference" "PR4255"
			(at 0 0 90)
			(layer "B.SilkS")
			(hide yes)
			(effects
				(font
					(size 1.27 1.27)
				)
				(justify mirror)
			)
		)
		(property "Value" ""
			(at 0 0 90)
			(layer "B.Fab")
			(effects
				(font
					(size 1.27 1.27)
				)
				(justify mirror)
			)
		)
		(duplicate_pad_numbers_are_jumpers no)
		(fp_line
			(start -0.7874 0.4064)
			(end 0.7874 0.4064)
			(stroke
				(width 0.1524)
				(type default)
			)
			(layer "B.SilkS")
		)
		(fp_line
			(start 0.7874 0.4064)
			(end 0.7874 -0.4064)
			(stroke
				(width 0.1524)
				(type default)
			)
			(layer "B.SilkS")
		)
		(fp_line
			(start -0.7874 -0.4064)
			(end -0.7874 0.4064)
			(stroke
				(width 0.1524)
				(type default)
			)
			(layer "B.SilkS")
		)
		(fp_line
			(start 0.7874 -0.4064)
			(end -0.7874 -0.4064)
			(stroke
				(width 0.1524)
				(type default)
			)
			(layer "B.SilkS")
		)
		(fp_line
			(start -0.67945 0.3048)
			(end -0.120396 0.3048)
			(stroke
				(width 0.1)
				(type default)
			)
			(layer "B.Fab")
		)
		(fp_line
			(start -0.120396 0.3048)
			(end -0.120396 0.2794)
			(stroke
				(width 0.1)
				(type default)
			)
			(layer "B.Fab")
		)
		(fp_line
			(start 0.12065 0.3048)
			(end 0.67945 0.3048)
			(stroke
				(width 0.1)
				(type default)
			)
			(layer "B.Fab")
		)
		(fp_line
			(start 0.67945 0.3048)
			(end 0.67945 -0.305054)
			(stroke
				(width 0.1)
				(type default)
			)
			(layer "B.Fab")
		)
		(fp_line
			(start -0.120396 0.2794)
			(end 0.12065 0.2794)
			(stroke
				(width 0.1)
				(type default)
			)
			(layer "B.Fab")
		)
		(fp_line
			(start 0.12065 0.2794)
			(end 0.12065 0.3048)
			(stroke
				(width 0.1)
				(type default)
			)
			(layer "B.Fab")
		)
		(fp_line
			(start -0.12065 -0.2794)
			(end -0.12065 -0.3048)
			(stroke
				(width 0.1)
				(type default)
			)
			(layer "B.Fab")
		)
		(fp_line
			(start 0.12065 -0.2794)
			(end -0.12065 -0.2794)
			(stroke
				(width 0.1)
				(type default)
			)
			(layer "B.Fab")
		)
		(fp_line
			(start -0.67945 -0.3048)
			(end -0.67945 0.3048)
			(stroke
				(width 0.1)
				(type default)
			)
			(layer "B.Fab")
		)
		(fp_line
			(start -0.12065 -0.3048)
			(end -0.67945 -0.3048)
			(stroke
				(width 0.1)
				(type default)
			)
			(layer "B.Fab")
		)
		(fp_line
			(start 0.12065 -0.305054)
			(end 0.12065 -0.2794)
			(stroke
				(width 0.1)
				(type default)
			)
			(layer "B.Fab")
		)
		(fp_line
			(start 0.67945 -0.305054)
			(end 0.12065 -0.305054)
			(stroke
				(width 0.1)
				(type default)
			)
			(layer "B.Fab")
		)
		(pad "1" smd circle
			(at 0.40005 0 90)
			(size 0 0)
			(layers "B.Cu" "B.Mask" "B.Paste")
			(net "NC_PVCCD_HV_CPU1_ACSP6")
		)
		(pad "2" smd circle
			(at -0.40005 0 90)
			(size 0 0)
			(layers "B.Cu" "B.Mask" "B.Paste")
			(net "GND")
		)
	)
	(footprint ""
		(layer "B.Cu")
		(at 103.596694 -237.794292 -90)
		(property "Reference" "C1389"
			(at 0 0 90)
			(layer "B.SilkS")
			(hide yes)
			(effects
				(font
					(size 1.27 1.27)
				)
				(justify mirror)
			)
		)
		(property "Value" ""
			(at 0 0 90)
			(layer "B.Fab")
			(effects
				(font
					(size 1.27 1.27)
				)
				(justify mirror)
			)
		)
		(duplicate_pad_numbers_are_jumpers no)
		(fp_line
			(start -1.2954 0.5842)
			(end 1.2954 0.5842)
			(stroke
				(width 0.1524)
				(type default)
			)
			(layer "B.SilkS")
		)
		(fp_line
			(start 1.2954 0.5842)
			(end 1.2954 -0.5842)
			(stroke
				(width 0.1524)
				(type default)
			)
			(layer "B.SilkS")
		)
		(fp_line
			(start -1.2954 -0.5842)
			(end -1.2954 0.5842)
			(stroke
				(width 0.1524)
				(type default)
			)
			(layer "B.SilkS")
		)
		(fp_line
			(start 0 -0.5842)
			(end 0 0.5842)
			(stroke
				(width 0.1524)
				(type default)
			)
			(layer "B.SilkS")
		)
		(fp_line
			(start 1.2954 -0.5842)
			(end -1.2954 -0.5842)
			(stroke
				(width 0.1524)
				(type default)
			)
			(layer "B.SilkS")
		)
		(fp_line
			(start -0.8636 0.4572)
			(end 0.8636 0.4572)
			(stroke
				(width 0.1)
				(type default)
			)
			(layer "B.Fab")
		)
		(fp_line
			(start 0.8636 0.4572)
			(end 0.8636 0.4064)
			(stroke
				(width 0.1)
				(type default)
			)
			(layer "B.Fab")
		)
		(fp_line
			(start -1.1938 0.4064)
			(end -0.8636 0.4064)
			(stroke
				(width 0.1)
				(type default)
			)
			(layer "B.Fab")
		)
		(fp_line
			(start -0.8636 0.4064)
			(end -0.8636 0.4572)
			(stroke
				(width 0.1)
				(type default)
			)
			(layer "B.Fab")
		)
		(fp_line
			(start 0.8636 0.4064)
			(end 1.1938 0.4064)
			(stroke
				(width 0.1)
				(type default)
			)
			(layer "B.Fab")
		)
		(fp_line
			(start 1.1938 0.4064)
			(end 1.1938 -0.4064)
			(stroke
				(width 0.1)
				(type default)
			)
			(layer "B.Fab")
		)
		(fp_line
			(start -1.1938 -0.4064)
			(end -1.1938 0.4064)
			(stroke
				(width 0.1)
				(type default)
			)
			(layer "B.Fab")
		)
		(fp_line
			(start -0.8636 -0.4064)
			(end -1.1938 -0.4064)
			(stroke
				(width 0.1)
				(type default)
			)
			(layer "B.Fab")
		)
		(fp_line
			(start 0.8636 -0.4064)
			(end 0.8636 -0.4572)
			(stroke
				(width 0.1)
				(type default)
			)
			(layer "B.Fab")
		)
		(fp_line
			(start 1.1938 -0.4064)
			(end 0.8636 -0.4064)
			(stroke
				(width 0.1)
				(type default)
			)
			(layer "B.Fab")
		)
		(fp_line
			(start -0.8636 -0.4572)
			(end -0.8636 -0.4064)
			(stroke
				(width 0.1)
				(type default)
			)
			(layer "B.Fab")
		)
		(fp_line
			(start 0.8636 -0.4572)
			(end -0.8636 -0.4572)
			(stroke
				(width 0.1)
				(type default)
			)
			(layer "B.Fab")
		)
		(pad "1" smd rect
			(at 0.7366 0 180)
			(size 0.7112 0.8128)
			(layers "B.Cu" "B.Mask" "B.Paste")
			(net "PVNN_MAIN_CPU1")
		)
		(pad "2" smd rect
			(at -0.7366 0 180)
			(size 0.7112 0.8128)
			(layers "B.Cu" "B.Mask" "B.Paste")
			(net "GND")
		)
	)
)
